(kicad_pcb
	(version 20260206)
	(generator "pcbnew")
	(generator_version "10.0")
	(general
		(thickness 1.6)
		(legacy_teardrops no)
	)
	(paper "A4")
	(title_block
		(title "panther-plus-userver — 13130-1b_20150205.brd")
		(comment 1 "Honey Badger (Wiwynn) / footprint 406 of 1509 (DIMM2), pads 1-8 of 210")
	)
	(layers
		(0 "F.Cu" signal "TOP")
		(4 "In1.Cu" signal "L2")
		(6 "In2.Cu" signal "L3")
		(8 "In3.Cu" signal "L4")
		(10 "In4.Cu" signal "L5")
		(12 "In5.Cu" signal "L6")
		(14 "In6.Cu" signal "L7")
		(16 "In7.Cu" signal "L8")
		(18 "In8.Cu" signal "L9")
		(20 "In9.Cu" signal "L10")
		(22 "In10.Cu" signal "L11")
		(2 "B.Cu" signal "BOTTOM")
		(9 "F.Adhes" user "F.Adhesive")
		(11 "B.Adhes" user "B.Adhesive")
		(13 "F.Paste" user "Package Geometry/Pastemask Top")
		(15 "B.Paste" user "Package Geometry/Pastemask Bottom")
		(5 "F.SilkS" user "Ref Des/Silkscreen Top")
		(7 "B.SilkS" user "Ref Des/Silkscreen Bottom")
		(1 "F.Mask" user "Board Geometry/Soldermask Top")
		(3 "B.Mask" user "Board Geometry/Soldermask Bottom")
		(17 "Dwgs.User" user "User.Drawings")
		(19 "Cmts.User" user "User.Comments")
		(21 "Eco1.User" user "User.Eco1")
		(23 "Eco2.User" user "User.Eco2")
		(25 "Edge.Cuts" user "Board Geometry/Outline")
		(27 "Margin" user)
		(31 "F.CrtYd" user "Package Geometry/Place Bound Top")
		(29 "B.CrtYd" user "Package Geometry/Place Bound Bottom")
		(35 "F.Fab" user "Ref Des/Assembly Top")
		(33 "B.Fab" user "Ref Des/Assembly Bottom")
	)
	(footprint ""
		(layer "F.Cu")
		(at 158.500064 -66.699892 180)
		(property "Reference" "DIMM2"
			(at 0 0 180)
			(layer "F.SilkS")
			(hide yes)
			(effects
				(font
					(size 1.27 1.27)
				)
			)
		)
		(property "Value" "DDR3-204P-174-COLAY-1-GP"
			(at -40.682164 -17.468088 180)
			(unlocked yes)
			(layer "F.Fab")
			(hide yes)
			(effects
				(font
					(size 1.016 1.016)
					(thickness 0.1524)
				)
			)
		)
		(property "Device Type" "AS0A626-H8SN-7H-COLAY-1"
			(at -40.682164 -18.992088 180)
			(unlocked yes)
			(layer "F.Fab")
			(hide yes)
			(effects
				(font
					(size 1.016 1.016)
					(thickness 0.1524)
				)
			)
		)
		(duplicate_pad_numbers_are_jumpers no)
		(pad "" np_thru_hole circle
			(at -33.399984 0 180)
			(size 0.254 0.254)
			(drill 1.6002)
			(layers "*.Cu" "*.Mask")
			(clearance 1.0287)
			(thermal_gap 1.0287)
		)
		(pad "" np_thru_hole circle
			(at 33.399984 0 180)
			(size 0.254 0.254)
			(drill 1.1176)
			(layers "*.Cu" "*.Mask")
			(clearance 0.7874)
			(thermal_gap 0.7874)
		)
		(pad "1" smd custom
			(at -31.649924 4.106672 180)
			(size 0.1143 0.1143)
			(layers "F.Cu" "F.Mask" "F.Paste")
			(net "DDR3_M_A_VREF_DQ1")
			(options
				(clearance outline)
				(anchor circle)
			)
			(primitives
				(gr_poly
					(pts
						(xy 0 0.9017) (xy -0.03175 0.89916) (xy -0.0635 0.889) (xy -0.09144 0.87376) (xy -0.11684 0.85344)
						(xy -0.13716 0.82804) (xy -0.1524 0.8001) (xy -0.16256 0.76835) (xy -0.1651 0.7366) (xy -0.1651 -0.13462)
						(xy -0.17272 -0.14224) (xy -0.19812 -0.1778) (xy -0.2032 -0.18796) (xy -0.20701 -0.19685) (xy -0.21209 -0.20701)
						(xy -0.2159 -0.21717) (xy -0.21844 -0.22733) (xy -0.22225 -0.23876) (xy -0.22352 -0.24892) (xy -0.22606 -0.25908)
						(xy -0.22733 -0.27051) (xy -0.22733 -0.28067) (xy -0.2286 -0.2921) (xy -0.22733 -0.30353) (xy -0.22733 -0.31369)
						(xy -0.22606 -0.32512) (xy -0.22352 -0.33528) (xy -0.22225 -0.34544) (xy -0.21844 -0.35687) (xy -0.2159 -0.36703)
						(xy -0.21209 -0.37719) (xy -0.20701 -0.38735) (xy -0.2032 -0.39624) (xy -0.19812 -0.4064) (xy -0.17272 -0.44196)
						(xy -0.1651 -0.44958) (xy -0.1651 -0.7366) (xy -0.16256 -0.76835) (xy -0.1524 -0.8001) (xy -0.13716 -0.82804)
						(xy -0.11684 -0.85344) (xy -0.09144 -0.87376) (xy -0.0635 -0.889) (xy -0.03175 -0.89916) (xy 0 -0.9017)
						(xy 0.03175 -0.89916) (xy 0.0635 -0.889) (xy 0.09144 -0.87376) (xy 0.11684 -0.85344) (xy 0.13716 -0.82804)
						(xy 0.1524 -0.8001) (xy 0.16256 -0.76835) (xy 0.1651 -0.7366) (xy 0.1651 -0.44958) (xy 0.17272 -0.44196)
						(xy 0.19812 -0.4064) (xy 0.2032 -0.39624) (xy 0.20701 -0.38735) (xy 0.21209 -0.37719) (xy 0.2159 -0.36703)
						(xy 0.21844 -0.35687) (xy 0.22225 -0.34544) (xy 0.22352 -0.33528) (xy 0.22606 -0.32512) (xy 0.22733 -0.31369)
						(xy 0.22733 -0.30353) (xy 0.2286 -0.2921) (xy 0.22733 -0.28067) (xy 0.22733 -0.27051) (xy 0.22606 -0.25908)
						(xy 0.22352 -0.24892) (xy 0.22225 -0.23876) (xy 0.21844 -0.22733) (xy 0.2159 -0.21717) (xy 0.21209 -0.20701)
						(xy 0.20701 -0.19685) (xy 0.2032 -0.18796) (xy 0.19812 -0.1778) (xy 0.17272 -0.14224) (xy 0.1651 -0.13462)
						(xy 0.1651 0.7366) (xy 0.16256 0.76835) (xy 0.1524 0.8001) (xy 0.13716 0.82804) (xy 0.11684 0.85344)
						(xy 0.09144 0.87376) (xy 0.0635 0.889) (xy 0.03175 0.89916)
					)
					(width 0)
					(fill yes)
				)
			)
		)
		(pad "2" smd custom
			(at -31.34995 -4.106672 180)
			(size 0.1143 0.1143)
			(layers "F.Cu" "F.Mask" "F.Paste")
			(net "GND")
			(options
				(clearance outline)
				(anchor circle)
			)
			(primitives
				(gr_poly
					(pts
						(xy 0 0.9017) (xy -0.03175 0.89916) (xy -0.0635 0.889) (xy -0.09144 0.87376) (xy -0.11684 0.85344)
						(xy -0.13716 0.82804) (xy -0.1524 0.8001) (xy -0.16256 0.76835) (xy -0.1651 0.7366) (xy -0.1651 0.44958)
						(xy -0.17272 0.44196) (xy -0.19812 0.4064) (xy -0.2032 0.39624) (xy -0.20701 0.38735) (xy -0.21209 0.37719)
						(xy -0.2159 0.36703) (xy -0.21844 0.35687) (xy -0.22225 0.34544) (xy -0.22352 0.33528) (xy -0.22606 0.32512)
						(xy -0.22733 0.31369) (xy -0.22733 0.30353) (xy -0.2286 0.2921) (xy -0.22733 0.28067) (xy -0.22733 0.27051)
						(xy -0.22606 0.25908) (xy -0.22352 0.24892) (xy -0.22225 0.23876) (xy -0.21844 0.22733) (xy -0.2159 0.21717)
						(xy -0.21209 0.20701) (xy -0.20701 0.19685) (xy -0.2032 0.18796) (xy -0.19812 0.1778) (xy -0.17272 0.14224)
						(xy -0.1651 0.13462) (xy -0.1651 -0.7366) (xy -0.16256 -0.76835) (xy -0.1524 -0.8001) (xy -0.13716 -0.82804)
						(xy -0.11684 -0.85344) (xy -0.09144 -0.87376) (xy -0.0635 -0.889) (xy -0.03175 -0.89916) (xy 0 -0.9017)
						(xy 0.03175 -0.89916) (xy 0.0635 -0.889) (xy 0.09144 -0.87376) (xy 0.11684 -0.85344) (xy 0.13716 -0.82804)
						(xy 0.1524 -0.8001) (xy 0.16256 -0.76835) (xy 0.1651 -0.7366) (xy 0.1651 0.13462) (xy 0.17272 0.14224)
						(xy 0.19812 0.1778) (xy 0.2032 0.18796) (xy 0.20701 0.19685) (xy 0.21209 0.20701) (xy 0.2159 0.21717)
						(xy 0.21844 0.22733) (xy 0.22225 0.23876) (xy 0.22352 0.24892) (xy 0.22606 0.25908) (xy 0.22733 0.27051)
						(xy 0.22733 0.28067) (xy 0.2286 0.2921) (xy 0.22733 0.30353) (xy 0.22733 0.31369) (xy 0.22606 0.32512)
						(xy 0.22352 0.33528) (xy 0.22225 0.34544) (xy 0.21844 0.35687) (xy 0.2159 0.36703) (xy 0.21209 0.37719)
						(xy 0.20701 0.38735) (xy 0.2032 0.39624) (xy 0.19812 0.4064) (xy 0.17272 0.44196) (xy 0.1651 0.44958)
						(xy 0.1651 0.7366) (xy 0.16256 0.76835) (xy 0.1524 0.8001) (xy 0.13716 0.82804) (xy 0.11684 0.85344)
						(xy 0.09144 0.87376) (xy 0.0635 0.889) (xy 0.03175 0.89916)
					)
					(width 0)
					(fill yes)
				)
			)
		)
		(pad "3" smd custom
			(at -31.049976 4.106672 180)
			(size 0.1143 0.1143)
			(layers "F.Cu" "F.Mask" "F.Paste")
			(net "GND")
			(options
				(clearance outline)
				(anchor circle)
			)
			(primitives
				(gr_poly
					(pts
						(xy 0 0.9017) (xy -0.03175 0.89916) (xy -0.0635 0.889) (xy -0.09144 0.87376) (xy -0.11684 0.85344)
						(xy -0.13716 0.82804) (xy -0.1524 0.8001) (xy -0.16256 0.76835) (xy -0.1651 0.7366) (xy -0.1651 0.11938)
						(xy -0.17272 0.11176) (xy -0.19812 0.0762) (xy -0.2032 0.06604) (xy -0.20701 0.05715) (xy -0.21209 0.04699)
						(xy -0.2159 0.03683) (xy -0.21844 0.02667) (xy -0.22225 0.01524) (xy -0.22352 0.00508) (xy -0.22606 -0.00508)
						(xy -0.22733 -0.01651) (xy -0.22733 -0.02667) (xy -0.2286 -0.0381) (xy -0.22733 -0.04953) (xy -0.22733 -0.05969)
						(xy -0.22606 -0.07112) (xy -0.22352 -0.08128) (xy -0.22225 -0.09144) (xy -0.21844 -0.10287) (xy -0.2159 -0.11303)
						(xy -0.21209 -0.12319) (xy -0.20701 -0.13335) (xy -0.2032 -0.14224) (xy -0.19812 -0.1524) (xy -0.17272 -0.18796)
						(xy -0.1651 -0.19558) (xy -0.1651 -0.7366) (xy -0.16256 -0.76835) (xy -0.1524 -0.8001) (xy -0.13716 -0.82804)
						(xy -0.11684 -0.85344) (xy -0.09144 -0.87376) (xy -0.0635 -0.889) (xy -0.03175 -0.89916) (xy 0 -0.9017)
						(xy 0.03175 -0.89916) (xy 0.0635 -0.889) (xy 0.09144 -0.87376) (xy 0.11684 -0.85344) (xy 0.13716 -0.82804)
						(xy 0.1524 -0.8001) (xy 0.16256 -0.76835) (xy 0.1651 -0.7366) (xy 0.1651 -0.19685) (xy 0.17272 -0.18923)
						(xy 0.17907 -0.18034) (xy 0.18669 -0.17145) (xy 0.19177 -0.16256) (xy 0.19812 -0.15367) (xy 0.20828 -0.13335)
						(xy 0.21971 -0.10287) (xy 0.22225 -0.09271) (xy 0.22479 -0.08128) (xy 0.22606 -0.07112) (xy 0.2286 -0.05969)
						(xy 0.2286 -0.01651) (xy 0.22606 -0.00508) (xy 0.22479 0.00508) (xy 0.22225 0.01651) (xy 0.21971 0.02667)
						(xy 0.20828 0.05715) (xy 0.19812 0.07747) (xy 0.19177 0.08636) (xy 0.18669 0.09525) (xy 0.17907 0.10414)
						(xy 0.17272 0.11303) (xy 0.1651 0.12065) (xy 0.1651 0.7366) (xy 0.16256 0.76835) (xy 0.1524 0.8001)
						(xy 0.13716 0.82804) (xy 0.11684 0.85344) (xy 0.09144 0.87376) (xy 0.0635 0.889) (xy 0.03175 0.89916)
					)
					(width 0)
					(fill yes)
				)
			)
		)
		(pad "4" smd custom
			(at -30.750002 -4.106672 180)
			(size 0.1143 0.1143)
			(layers "F.Cu" "F.Mask" "F.Paste")
			(net "M_A_DQ0")
			(options
				(clearance outline)
				(anchor circle)
			)
			(primitives
				(gr_poly
					(pts
						(xy 0 0.9017) (xy -0.03175 0.89916) (xy -0.0635 0.889) (xy -0.09144 0.87376) (xy -0.11684 0.85344)
						(xy -0.13716 0.82804) (xy -0.1524 0.8001) (xy -0.16256 0.76835) (xy -0.1651 0.7366) (xy -0.1651 0.19685)
						(xy -0.17272 0.18923) (xy -0.17907 0.18034) (xy -0.18669 0.17145) (xy -0.19177 0.16256) (xy -0.19812 0.15367)
						(xy -0.20828 0.13335) (xy -0.21971 0.10287) (xy -0.22225 0.09271) (xy -0.22479 0.08128) (xy -0.22606 0.07112)
						(xy -0.2286 0.05969) (xy -0.2286 0.01651) (xy -0.22606 0.00508) (xy -0.22479 -0.00508) (xy -0.22225 -0.01651)
						(xy -0.21971 -0.02667) (xy -0.20828 -0.05715) (xy -0.19812 -0.07747) (xy -0.19177 -0.08636) (xy -0.18669 -0.09525)
						(xy -0.17907 -0.10414) (xy -0.17272 -0.11303) (xy -0.1651 -0.12065) (xy -0.1651 -0.7366) (xy -0.16256 -0.76835)
						(xy -0.1524 -0.8001) (xy -0.13716 -0.82804) (xy -0.11684 -0.85344) (xy -0.09144 -0.87376) (xy -0.0635 -0.889)
						(xy -0.03175 -0.89916) (xy 0 -0.9017) (xy 0.03175 -0.89916) (xy 0.0635 -0.889) (xy 0.09144 -0.87376)
						(xy 0.11684 -0.85344) (xy 0.13716 -0.82804) (xy 0.1524 -0.8001) (xy 0.16256 -0.76835) (xy 0.1651 -0.7366)
						(xy 0.1651 -0.11938) (xy 0.17272 -0.11176) (xy 0.19812 -0.0762) (xy 0.2032 -0.06604) (xy 0.20701 -0.05715)
						(xy 0.21209 -0.04699) (xy 0.2159 -0.03683) (xy 0.21844 -0.02667) (xy 0.22225 -0.01524) (xy 0.22352 -0.00508)
						(xy 0.22606 0.00508) (xy 0.22733 0.01651) (xy 0.22733 0.02667) (xy 0.2286 0.0381) (xy 0.22733 0.04953)
						(xy 0.22733 0.05969) (xy 0.22606 0.07112) (xy 0.22352 0.08128) (xy 0.22225 0.09144) (xy 0.21844 0.10287)
						(xy 0.2159 0.11303) (xy 0.21209 0.12319) (xy 0.20701 0.13335) (xy 0.2032 0.14224) (xy 0.19812 0.1524)
						(xy 0.17272 0.18796) (xy 0.1651 0.19558) (xy 0.1651 0.7366) (xy 0.16256 0.76835) (xy 0.1524 0.8001)
						(xy 0.13716 0.82804) (xy 0.11684 0.85344) (xy 0.09144 0.87376) (xy 0.0635 0.889) (xy 0.03175 0.89916)
					)
					(width 0)
					(fill yes)
				)
			)
		)
		(pad "5" smd custom
			(at -30.450028 4.106672 180)
			(size 0.1143 0.1143)
			(layers "F.Cu" "F.Mask" "F.Paste")
			(net "M_A_DQ4")
			(options
				(clearance outline)
				(anchor circle)
			)
			(primitives
				(gr_poly
					(pts
						(xy 0 0.9017) (xy -0.03175 0.89916) (xy -0.0635 0.889) (xy -0.09144 0.87376) (xy -0.11684 0.85344)
						(xy -0.13716 0.82804) (xy -0.1524 0.8001) (xy -0.16256 0.76835) (xy -0.1651 0.7366) (xy -0.1651 -0.13462)
						(xy -0.17272 -0.14224) (xy -0.19812 -0.1778) (xy -0.2032 -0.18796) (xy -0.20701 -0.19685) (xy -0.21209 -0.20701)
						(xy -0.2159 -0.21717) (xy -0.21844 -0.22733) (xy -0.22225 -0.23876) (xy -0.22352 -0.24892) (xy -0.22606 -0.25908)
						(xy -0.22733 -0.27051) (xy -0.22733 -0.28067) (xy -0.2286 -0.2921) (xy -0.22733 -0.30353) (xy -0.22733 -0.31369)
						(xy -0.22606 -0.32512) (xy -0.22352 -0.33528) (xy -0.22225 -0.34544) (xy -0.21844 -0.35687) (xy -0.2159 -0.36703)
						(xy -0.21209 -0.37719) (xy -0.20701 -0.38735) (xy -0.2032 -0.39624) (xy -0.19812 -0.4064) (xy -0.17272 -0.44196)
						(xy -0.1651 -0.44958) (xy -0.1651 -0.7366) (xy -0.16256 -0.76835) (xy -0.1524 -0.8001) (xy -0.13716 -0.82804)
						(xy -0.11684 -0.85344) (xy -0.09144 -0.87376) (xy -0.0635 -0.889) (xy -0.03175 -0.89916) (xy 0 -0.9017)
						(xy 0.03175 -0.89916) (xy 0.0635 -0.889) (xy 0.09144 -0.87376) (xy 0.11684 -0.85344) (xy 0.13716 -0.82804)
						(xy 0.1524 -0.8001) (xy 0.16256 -0.76835) (xy 0.1651 -0.7366) (xy 0.1651 -0.44958) (xy 0.17272 -0.44196)
						(xy 0.19812 -0.4064) (xy 0.2032 -0.39624) (xy 0.20701 -0.38735) (xy 0.21209 -0.37719) (xy 0.2159 -0.36703)
						(xy 0.21844 -0.35687) (xy 0.22225 -0.34544) (xy 0.22352 -0.33528) (xy 0.22606 -0.32512) (xy 0.22733 -0.31369)
						(xy 0.22733 -0.30353) (xy 0.2286 -0.2921) (xy 0.22733 -0.28067) (xy 0.22733 -0.27051) (xy 0.22606 -0.25908)
						(xy 0.22352 -0.24892) (xy 0.22225 -0.23876) (xy 0.21844 -0.22733) (xy 0.2159 -0.21717) (xy 0.21209 -0.20701)
						(xy 0.20701 -0.19685) (xy 0.2032 -0.18796) (xy 0.19812 -0.1778) (xy 0.17272 -0.14224) (xy 0.1651 -0.13462)
						(xy 0.1651 0.7366) (xy 0.16256 0.76835) (xy 0.1524 0.8001) (xy 0.13716 0.82804) (xy 0.11684 0.85344)
						(xy 0.09144 0.87376) (xy 0.0635 0.889) (xy 0.03175 0.89916)
					)
					(width 0)
					(fill yes)
				)
			)
		)
		(pad "6" smd custom
			(at -30.150054 -4.106672 180)
			(size 0.1143 0.1143)
			(layers "F.Cu" "F.Mask" "F.Paste")
			(net "M_A_DQ1")
			(options
				(clearance outline)
				(anchor circle)
			)
			(primitives
				(gr_poly
					(pts
						(xy 0 0.9017) (xy -0.03175 0.89916) (xy -0.0635 0.889) (xy -0.09144 0.87376) (xy -0.11684 0.85344)
						(xy -0.13716 0.82804) (xy -0.1524 0.8001) (xy -0.16256 0.76835) (xy -0.1651 0.7366) (xy -0.1651 0.44958)
						(xy -0.17272 0.44196) (xy -0.19812 0.4064) (xy -0.2032 0.39624) (xy -0.20701 0.38735) (xy -0.21209 0.37719)
						(xy -0.2159 0.36703) (xy -0.21844 0.35687) (xy -0.22225 0.34544) (xy -0.22352 0.33528) (xy -0.22606 0.32512)
						(xy -0.22733 0.31369) (xy -0.22733 0.30353) (xy -0.2286 0.2921) (xy -0.22733 0.28067) (xy -0.22733 0.27051)
						(xy -0.22606 0.25908) (xy -0.22352 0.24892) (xy -0.22225 0.23876) (xy -0.21844 0.22733) (xy -0.2159 0.21717)
						(xy -0.21209 0.20701) (xy -0.20701 0.19685) (xy -0.2032 0.18796) (xy -0.19812 0.1778) (xy -0.17272 0.14224)
						(xy -0.1651 0.13462) (xy -0.1651 -0.7366) (xy -0.16256 -0.76835) (xy -0.1524 -0.8001) (xy -0.13716 -0.82804)
						(xy -0.11684 -0.85344) (xy -0.09144 -0.87376) (xy -0.0635 -0.889) (xy -0.03175 -0.89916) (xy 0 -0.9017)
						(xy 0.03175 -0.89916) (xy 0.0635 -0.889) (xy 0.09144 -0.87376) (xy 0.11684 -0.85344) (xy 0.13716 -0.82804)
						(xy 0.1524 -0.8001) (xy 0.16256 -0.76835) (xy 0.1651 -0.7366) (xy 0.1651 0.13462) (xy 0.17272 0.14224)
						(xy 0.19812 0.1778) (xy 0.2032 0.18796) (xy 0.20701 0.19685) (xy 0.21209 0.20701) (xy 0.2159 0.21717)
						(xy 0.21844 0.22733) (xy 0.22225 0.23876) (xy 0.22352 0.24892) (xy 0.22606 0.25908) (xy 0.22733 0.27051)
						(xy 0.22733 0.28067) (xy 0.2286 0.2921) (xy 0.22733 0.30353) (xy 0.22733 0.31369) (xy 0.22606 0.32512)
						(xy 0.22352 0.33528) (xy 0.22225 0.34544) (xy 0.21844 0.35687) (xy 0.2159 0.36703) (xy 0.21209 0.37719)
						(xy 0.20701 0.38735) (xy 0.2032 0.39624) (xy 0.19812 0.4064) (xy 0.17272 0.44196) (xy 0.1651 0.44958)
						(xy 0.1651 0.7366) (xy 0.16256 0.76835) (xy 0.1524 0.8001) (xy 0.13716 0.82804) (xy 0.11684 0.85344)
						(xy 0.09144 0.87376) (xy 0.0635 0.889) (xy 0.03175 0.89916)
					)
					(width 0)
					(fill yes)
				)
			)
		)
	)
)
